(kicad_pcb
	(version 20260206)
	(generator "pcbnew")
	(generator_version "10.0")
	(general
		(thickness 1.6)
		(legacy_teardrops no)
	)
	(paper "A4")
	(title_block
		(title "v1-chassis-manager — T6M_CM_d_v01_1031_1645.brd")
		(comment 1 "Open CloudServer (Microsoft) / footprints 1623-1632 of 2512")
	)
	(layers
		(0 "F.Cu" signal "TOP")
		(4 "In1.Cu" signal "GND1")
		(6 "In2.Cu" signal "IN1")
		(8 "In3.Cu" signal "VCC1")
		(10 "In4.Cu" signal "VCC2")
		(12 "In5.Cu" signal "GND2")
		(14 "In6.Cu" signal "IN2")
		(16 "In7.Cu" signal "IN3")
		(18 "In8.Cu" signal "GND3")
		(2 "B.Cu" signal "BOTTOM")
		(9 "F.Adhes" user "F.Adhesive")
		(11 "B.Adhes" user "B.Adhesive")
		(13 "F.Paste" user "Package Geometry/Pastemask Top")
		(15 "B.Paste" user "Package Geometry/Pastemask Bottom")
		(5 "F.SilkS" user "Ref Des/Silkscreen Top")
		(7 "B.SilkS" user "Ref Des/Silkscreen Bottom")
		(1 "F.Mask" user "Board Geometry/Soldermask Top")
		(3 "B.Mask" user "Board Geometry/Soldermask Bottom")
		(17 "Dwgs.User" user "User.Drawings")
		(19 "Cmts.User" user "User.Comments")
		(21 "Eco1.User" user "User.Eco1")
		(23 "Eco2.User" user "User.Eco2")
		(25 "Edge.Cuts" user "Board Geometry/Outline")
		(27 "Margin" user)
		(31 "F.CrtYd" user "Package Geometry/Place Bound Top")
		(29 "B.CrtYd" user "Package Geometry/Place Bound Bottom")
		(35 "F.Fab" user "Ref Des/Assembly Top")
		(33 "B.Fab" user "Ref Des/Assembly Bottom")
	)
	(footprint ""
		(layer "B.Cu")
		(at 135.196834 -37.375084 180)
		(property "Reference" "R1188"
			(at 5.415788 -18.226532 0)
			(unlocked yes)
			(layer "B.SilkS")
			(effects
				(font
					(size 0.7874 0.5842)
					(thickness 0.1524)
				)
				(justify left mirror)
			)
		)
		(property "Value" ""
			(at 0 0 0)
			(layer "B.Fab")
			(effects
				(font
					(size 1.27 1.27)
				)
				(justify mirror)
			)
		)
		(duplicate_pad_numbers_are_jumpers no)
		(fp_line
			(start 0.7874 0.4064)
			(end 0.7874 -0.4064)
			(stroke
				(width 0.1524)
				(type default)
			)
			(layer "B.SilkS")
		)
		(fp_line
			(start 0.7874 -0.4064)
			(end -0.7874 -0.4064)
			(stroke
				(width 0.1524)
				(type default)
			)
			(layer "B.SilkS")
		)
		(fp_line
			(start -0.7874 0.4064)
			(end 0.7874 0.4064)
			(stroke
				(width 0.1524)
				(type default)
			)
			(layer "B.SilkS")
		)
		(fp_line
			(start -0.7874 -0.4064)
			(end -0.7874 0.4064)
			(stroke
				(width 0.1524)
				(type default)
			)
			(layer "B.SilkS")
		)
		(fp_poly
			(pts
				(xy 0.508 0.2794) (xy 0.508 0.2286) (xy 0.635 0.2286) (xy 0.635 -0.254) (xy 0.5334 -0.254) (xy 0.5334 -0.2794)
				(xy -0.5334 -0.2794) (xy -0.5334 -0.254) (xy -0.635 -0.254) (xy -0.635 0.254) (xy -0.5334 0.254)
				(xy -0.5334 0.2794)
			)
			(stroke
				(width 0)
				(type default)
			)
			(fill no)
			(layer "B.CrtYd")
		)
		(pad "1" smd rect
			(at -0.40005 0)
			(size 0.4572 0.508)
			(layers "B.Cu" "B.Mask" "B.Paste")
			(net "SIO_JTAG_CPLD2_TDI")
		)
		(pad "2" smd rect
			(at 0.40005 0)
			(size 0.4572 0.508)
			(layers "B.Cu" "B.Mask" "B.Paste")
			(net "GND")
		)
	)
	(footprint ""
		(layer "B.Cu")
		(at 169.134028 -154.804872 180)
		(property "Reference" "R581"
			(at -4.380992 -0.115316 0)
			(unlocked yes)
			(layer "B.SilkS")
			(effects
				(font
					(size 0.7874 0.5842)
					(thickness 0.1524)
				)
				(justify left mirror)
			)
		)
		(property "Value" ""
			(at 0 0 0)
			(layer "B.Fab")
			(effects
				(font
					(size 1.27 1.27)
				)
				(justify mirror)
			)
		)
		(duplicate_pad_numbers_are_jumpers no)
		(fp_line
			(start 0.7874 0.4064)
			(end 0.7874 -0.4064)
			(stroke
				(width 0.1524)
				(type default)
			)
			(layer "B.SilkS")
		)
		(fp_line
			(start 0.7874 -0.4064)
			(end -0.7874 -0.4064)
			(stroke
				(width 0.1524)
				(type default)
			)
			(layer "B.SilkS")
		)
		(fp_line
			(start -0.7874 0.4064)
			(end 0.7874 0.4064)
			(stroke
				(width 0.1524)
				(type default)
			)
			(layer "B.SilkS")
		)
		(fp_line
			(start -0.7874 -0.4064)
			(end -0.7874 0.4064)
			(stroke
				(width 0.1524)
				(type default)
			)
			(layer "B.SilkS")
		)
		(fp_poly
			(pts
				(xy 0.508 0.2794) (xy 0.508 0.2286) (xy 0.635 0.2286) (xy 0.635 -0.254) (xy 0.5334 -0.254) (xy 0.5334 -0.2794)
				(xy -0.5334 -0.2794) (xy -0.5334 -0.254) (xy -0.635 -0.254) (xy -0.635 0.254) (xy -0.5334 0.254)
				(xy -0.5334 0.2794)
			)
			(stroke
				(width 0)
				(type default)
			)
			(fill no)
			(layer "B.CrtYd")
		)
		(pad "1" smd rect
			(at -0.40005 0)
			(size 0.4572 0.508)
			(layers "B.Cu" "B.Mask" "B.Paste")
			(net "P3V3_NODE1")
		)
		(pad "2" smd rect
			(at 0.40005 0)
			(size 0.4572 0.508)
			(layers "B.Cu" "B.Mask" "B.Paste")
			(net "LAN2_DIS_REG10")
		)
	)
	(footprint ""
		(layer "B.Cu")
		(at 46.56582 -150.27529 90)
		(property "Reference" "C422"
			(at 7.935214 -13.231622 270)
			(unlocked yes)
			(layer "B.SilkS")
			(effects
				(font
					(size 0.7874 0.5842)
					(thickness 0.1524)
				)
				(justify left mirror)
			)
		)
		(property "Value" ""
			(at 0 0 90)
			(layer "B.Fab")
			(effects
				(font
					(size 1.27 1.27)
				)
				(justify mirror)
			)
		)
		(duplicate_pad_numbers_are_jumpers no)
		(fp_line
			(start 0.7874 -0.4064)
			(end -0.7874 -0.4064)
			(stroke
				(width 0.1524)
				(type default)
			)
			(layer "B.SilkS")
		)
		(fp_line
			(start -0.7874 -0.4064)
			(end -0.7874 0.4064)
			(stroke
				(width 0.1524)
				(type default)
			)
			(layer "B.SilkS")
		)
		(fp_line
			(start 0 0.381)
			(end 0 -0.381)
			(stroke
				(width 0.1524)
				(type default)
			)
			(layer "B.SilkS")
		)
		(fp_line
			(start 0.7874 0.4064)
			(end 0.7874 -0.4064)
			(stroke
				(width 0.1524)
				(type default)
			)
			(layer "B.SilkS")
		)
		(fp_line
			(start -0.7874 0.4064)
			(end 0.7874 0.4064)
			(stroke
				(width 0.1524)
				(type default)
			)
			(layer "B.SilkS")
		)
		(fp_poly
			(pts
				(xy 0.5334 0.254) (xy 0.635 0.254) (xy 0.635 0.2286) (xy 0.635 -0.254) (xy 0.5334 -0.254) (xy 0.5334 -0.2794)
				(xy -0.5334 -0.2794) (xy -0.5334 -0.254) (xy -0.635 -0.254) (xy -0.635 0.254) (xy -0.5334 0.254)
				(xy -0.5334 0.2794) (xy 0.508 0.2794) (xy 0.5334 0.2794)
			)
			(stroke
				(width 0)
				(type default)
			)
			(fill no)
			(layer "B.CrtYd")
		)
		(pad "1" smd rect
			(at -0.40005 0 270)
			(size 0.4572 0.508)
			(layers "B.Cu" "B.Mask" "B.Paste")
			(net "P1V05_LAN1")
		)
		(pad "2" smd rect
			(at 0.40005 0 270)
			(size 0.4572 0.508)
			(layers "B.Cu" "B.Mask" "B.Paste")
			(net "GND")
		)
	)
	(footprint ""
		(layer "B.Cu")
		(at 69.649086 -124.930662 -90)
		(property "Reference" "C278"
			(at 3.666744 -8.660384 270)
			(unlocked yes)
			(layer "B.SilkS")
			(effects
				(font
					(size 0.7874 0.5842)
					(thickness 0.1524)
				)
				(justify left mirror)
			)
		)
		(property "Value" ""
			(at 0 0 90)
			(layer "B.Fab")
			(effects
				(font
					(size 1.27 1.27)
				)
				(justify mirror)
			)
		)
		(duplicate_pad_numbers_are_jumpers no)
		(fp_line
			(start -0.7874 0.4064)
			(end 0.7874 0.4064)
			(stroke
				(width 0.1524)
				(type default)
			)
			(layer "B.SilkS")
		)
		(fp_line
			(start 0.7874 0.4064)
			(end 0.7874 -0.4064)
			(stroke
				(width 0.1524)
				(type default)
			)
			(layer "B.SilkS")
		)
		(fp_line
			(start 0 0.381)
			(end 0 -0.381)
			(stroke
				(width 0.1524)
				(type default)
			)
			(layer "B.SilkS")
		)
		(fp_line
			(start -0.7874 -0.4064)
			(end -0.7874 0.4064)
			(stroke
				(width 0.1524)
				(type default)
			)
			(layer "B.SilkS")
		)
		(fp_line
			(start 0.7874 -0.4064)
			(end -0.7874 -0.4064)
			(stroke
				(width 0.1524)
				(type default)
			)
			(layer "B.SilkS")
		)
		(fp_poly
			(pts
				(xy 0.5334 0.254) (xy 0.635 0.254) (xy 0.635 0.2286) (xy 0.635 -0.254) (xy 0.5334 -0.254) (xy 0.5334 -0.2794)
				(xy -0.5334 -0.2794) (xy -0.5334 -0.254) (xy -0.635 -0.254) (xy -0.635 0.254) (xy -0.5334 0.254)
				(xy -0.5334 0.2794) (xy 0.508 0.2794) (xy 0.5334 0.2794)
			)
			(stroke
				(width 0)
				(type default)
			)
			(fill no)
			(layer "B.CrtYd")
		)
		(pad "1" smd rect
			(at -0.40005 0 90)
			(size 0.4572 0.508)
			(layers "B.Cu" "B.Mask" "B.Paste")
			(net "BMC_NODE1_VCC_1V8_PCIE")
		)
		(pad "2" smd rect
			(at 0.40005 0 90)
			(size 0.4572 0.508)
			(layers "B.Cu" "B.Mask" "B.Paste")
			(net "GND")
		)
	)
	(footprint ""
		(layer "B.Cu")
		(at 66.52133 -138.966448 180)
		(property "Reference" "C291"
			(at 37.32784 -54.78907 0)
			(unlocked yes)
			(layer "B.SilkS")
			(effects
				(font
					(size 0.7874 0.5842)
					(thickness 0.1524)
				)
				(justify left mirror)
			)
		)
		(property "Value" ""
			(at 0 0 0)
			(layer "B.Fab")
			(effects
				(font
					(size 1.27 1.27)
				)
				(justify mirror)
			)
		)
		(duplicate_pad_numbers_are_jumpers no)
		(fp_line
			(start 0.7874 0.4064)
			(end 0.7874 -0.4064)
			(stroke
				(width 0.1524)
				(type default)
			)
			(layer "B.SilkS")
		)
		(fp_line
			(start 0.7874 -0.4064)
			(end -0.7874 -0.4064)
			(stroke
				(width 0.1524)
				(type default)
			)
			(layer "B.SilkS")
		)
		(fp_line
			(start 0 0.381)
			(end 0 -0.381)
			(stroke
				(width 0.1524)
				(type default)
			)
			(layer "B.SilkS")
		)
		(fp_line
			(start -0.7874 0.4064)
			(end 0.7874 0.4064)
			(stroke
				(width 0.1524)
				(type default)
			)
			(layer "B.SilkS")
		)
		(fp_line
			(start -0.7874 -0.4064)
			(end -0.7874 0.4064)
			(stroke
				(width 0.1524)
				(type default)
			)
			(layer "B.SilkS")
		)
		(fp_poly
			(pts
				(xy 0.5334 0.254) (xy 0.635 0.254) (xy 0.635 0.2286) (xy 0.635 -0.254) (xy 0.5334 -0.254) (xy 0.5334 -0.2794)
				(xy -0.5334 -0.2794) (xy -0.5334 -0.254) (xy -0.635 -0.254) (xy -0.635 0.254) (xy -0.5334 0.254)
				(xy -0.5334 0.2794) (xy 0.508 0.2794) (xy 0.5334 0.2794)
			)
			(stroke
				(width 0)
				(type default)
			)
			(fill no)
			(layer "B.CrtYd")
		)
		(pad "1" smd rect
			(at -0.40005 0)
			(size 0.4572 0.508)
			(layers "B.Cu" "B.Mask" "B.Paste")
			(net "P1V26_BMC_NODE1")
		)
		(pad "2" smd rect
			(at 0.40005 0)
			(size 0.4572 0.508)
			(layers "B.Cu" "B.Mask" "B.Paste")
			(net "GND")
		)
	)
	(footprint ""
		(layer "B.Cu")
		(at 128.701546 -38.274244)
		(property "Reference" "R1207"
			(at 0.419354 7.550912 0)
			(unlocked yes)
			(layer "B.SilkS")
			(effects
				(font
					(size 0.7874 0.5842)
					(thickness 0.1524)
				)
				(justify left mirror)
			)
		)
		(property "Value" ""
			(at 0 0 0)
			(layer "B.Fab")
			(effects
				(font
					(size 1.27 1.27)
				)
				(justify mirror)
			)
		)
		(duplicate_pad_numbers_are_jumpers no)
		(fp_line
			(start -0.7874 -0.4064)
			(end -0.7874 0.4064)
			(stroke
				(width 0.1524)
				(type default)
			)
			(layer "B.SilkS")
		)
		(fp_line
			(start -0.7874 0.4064)
			(end 0.7874 0.4064)
			(stroke
				(width 0.1524)
				(type default)
			)
			(layer "B.SilkS")
		)
		(fp_line
			(start 0.7874 -0.4064)
			(end -0.7874 -0.4064)
			(stroke
				(width 0.1524)
				(type default)
			)
			(layer "B.SilkS")
		)
		(fp_line
			(start 0.7874 0.4064)
			(end 0.7874 -0.4064)
			(stroke
				(width 0.1524)
				(type default)
			)
			(layer "B.SilkS")
		)
		(fp_poly
			(pts
				(xy 0.508 0.2794) (xy 0.508 0.2286) (xy 0.635 0.2286) (xy 0.635 -0.254) (xy 0.5334 -0.254) (xy 0.5334 -0.2794)
				(xy -0.5334 -0.2794) (xy -0.5334 -0.254) (xy -0.635 -0.254) (xy -0.635 0.254) (xy -0.5334 0.254)
				(xy -0.5334 0.2794)
			)
			(stroke
				(width 0)
				(type default)
			)
			(fill no)
			(layer "B.CrtYd")
		)
		(pad "1" smd rect
			(at -0.40005 0 180)
			(size 0.4572 0.508)
			(layers "B.Cu" "B.Mask" "B.Paste")
			(net "SIO_JTAG_CPLD3_TCK_R")
		)
		(pad "2" smd rect
			(at 0.40005 0 180)
			(size 0.4572 0.508)
			(layers "B.Cu" "B.Mask" "B.Paste")
			(net "SIO_JTAG_CPLD3_TCK")
		)
	)
	(footprint ""
		(layer "B.Cu")
		(at 143.36776 -184.951624 90)
		(property "Reference" "R972"
			(at 4.392676 -2.31775 270)
			(unlocked yes)
			(layer "B.SilkS")
			(effects
				(font
					(size 0.7874 0.5842)
					(thickness 0.1524)
				)
				(justify left mirror)
			)
		)
		(property "Value" ""
			(at 0 0 90)
			(layer "B.Fab")
			(effects
				(font
					(size 1.27 1.27)
				)
				(justify mirror)
			)
		)
		(duplicate_pad_numbers_are_jumpers no)
		(fp_line
			(start 0.7874 -0.4064)
			(end -0.7874 -0.4064)
			(stroke
				(width 0.1524)
				(type default)
			)
			(layer "B.SilkS")
		)
		(fp_line
			(start -0.7874 -0.4064)
			(end -0.7874 0.4064)
			(stroke
				(width 0.1524)
				(type default)
			)
			(layer "B.SilkS")
		)
		(fp_line
			(start 0.7874 0.4064)
			(end 0.7874 -0.4064)
			(stroke
				(width 0.1524)
				(type default)
			)
			(layer "B.SilkS")
		)
		(fp_line
			(start -0.7874 0.4064)
			(end 0.7874 0.4064)
			(stroke
				(width 0.1524)
				(type default)
			)
			(layer "B.SilkS")
		)
		(fp_poly
			(pts
				(xy 0.508 0.2794) (xy 0.508 0.2286) (xy 0.635 0.2286) (xy 0.635 -0.254) (xy 0.5334 -0.254) (xy 0.5334 -0.2794)
				(xy -0.5334 -0.2794) (xy -0.5334 -0.254) (xy -0.635 -0.254) (xy -0.635 0.254) (xy -0.5334 0.254)
				(xy -0.5334 0.2794)
			)
			(stroke
				(width 0)
				(type default)
			)
			(fill no)
			(layer "B.CrtYd")
		)
		(pad "1" smd rect
			(at -0.40005 0 270)
			(size 0.4572 0.508)
			(layers "B.Cu" "B.Mask" "B.Paste")
			(net "UART_T11_NODE3_TXD")
		)
		(pad "2" smd rect
			(at 0.40005 0 270)
			(size 0.4572 0.508)
			(layers "B.Cu" "B.Mask" "B.Paste")
			(net "UART_T11_NODE3_TXD_R")
		)
	)
	(footprint ""
		(layer "B.Cu")
		(at 59.694572 -79.912718 90)
		(property "Reference" "C98"
			(at -32.491426 -14.379702 270)
			(unlocked yes)
			(layer "B.SilkS")
			(effects
				(font
					(size 0.7874 0.5842)
					(thickness 0.1524)
				)
				(justify left mirror)
			)
		)
		(property "Value" ""
			(at 0 0 90)
			(layer "B.Fab")
			(effects
				(font
					(size 1.27 1.27)
				)
				(justify mirror)
			)
		)
		(duplicate_pad_numbers_are_jumpers no)
		(fp_line
			(start 0.7874 -0.4064)
			(end -0.7874 -0.4064)
			(stroke
				(width 0.1524)
				(type default)
			)
			(layer "B.SilkS")
		)
		(fp_line
			(start -0.7874 -0.4064)
			(end -0.7874 0.4064)
			(stroke
				(width 0.1524)
				(type default)
			)
			(layer "B.SilkS")
		)
		(fp_line
			(start 0 0.381)
			(end 0 -0.381)
			(stroke
				(width 0.1524)
				(type default)
			)
			(layer "B.SilkS")
		)
		(fp_line
			(start 0.7874 0.4064)
			(end 0.7874 -0.4064)
			(stroke
				(width 0.1524)
				(type default)
			)
			(layer "B.SilkS")
		)
		(fp_line
			(start -0.7874 0.4064)
			(end 0.7874 0.4064)
			(stroke
				(width 0.1524)
				(type default)
			)
			(layer "B.SilkS")
		)
		(fp_poly
			(pts
				(xy 0.5334 0.254) (xy 0.635 0.254) (xy 0.635 0.2286) (xy 0.635 -0.254) (xy 0.5334 -0.254) (xy 0.5334 -0.2794)
				(xy -0.5334 -0.2794) (xy -0.5334 -0.254) (xy -0.635 -0.254) (xy -0.635 0.254) (xy -0.5334 0.254)
				(xy -0.5334 0.2794) (xy 0.508 0.2794) (xy 0.5334 0.2794)
			)
			(stroke
				(width 0)
				(type default)
			)
			(fill no)
			(layer "B.CrtYd")
		)
		(pad "1" smd rect
			(at -0.40005 0 270)
			(size 0.4572 0.508)
			(layers "B.Cu" "B.Mask" "B.Paste")
			(net "P1V05_NODE1")
		)
		(pad "2" smd rect
			(at 0.40005 0 270)
			(size 0.4572 0.508)
			(layers "B.Cu" "B.Mask" "B.Paste")
			(net "GND")
		)
	)
	(footprint ""
		(layer "B.Cu")
		(at 110.44936 -173.521624 180)
		(property "Reference" "R718"
			(at 21.356828 -32.269176 0)
			(unlocked yes)
			(layer "B.SilkS")
			(effects
				(font
					(size 0.7874 0.5842)
					(thickness 0.1524)
				)
				(justify left mirror)
			)
		)
		(property "Value" ""
			(at 0 0 0)
			(layer "B.Fab")
			(effects
				(font
					(size 1.27 1.27)
				)
				(justify mirror)
			)
		)
		(duplicate_pad_numbers_are_jumpers no)
		(fp_line
			(start 0.7874 0.4064)
			(end 0.7874 -0.4064)
			(stroke
				(width 0.1524)
				(type default)
			)
			(layer "B.SilkS")
		)
		(fp_line
			(start 0.7874 -0.4064)
			(end -0.7874 -0.4064)
			(stroke
				(width 0.1524)
				(type default)
			)
			(layer "B.SilkS")
		)
		(fp_line
			(start -0.7874 0.4064)
			(end 0.7874 0.4064)
			(stroke
				(width 0.1524)
				(type default)
			)
			(layer "B.SilkS")
		)
		(fp_line
			(start -0.7874 -0.4064)
			(end -0.7874 0.4064)
			(stroke
				(width 0.1524)
				(type default)
			)
			(layer "B.SilkS")
		)
		(fp_poly
			(pts
				(xy 0.508 0.2794) (xy 0.508 0.2286) (xy 0.635 0.2286) (xy 0.635 -0.254) (xy 0.5334 -0.254) (xy 0.5334 -0.2794)
				(xy -0.5334 -0.2794) (xy -0.5334 -0.254) (xy -0.635 -0.254) (xy -0.635 0.254) (xy -0.5334 0.254)
				(xy -0.5334 0.2794)
			)
			(stroke
				(width 0)
				(type default)
			)
			(fill no)
			(layer "B.CrtYd")
		)
		(pad "1" smd rect
			(at -0.40005 0)
			(size 0.4572 0.508)
			(layers "B.Cu" "B.Mask" "B.Paste")
			(net "N21699716")
		)
		(pad "2" smd rect
			(at 0.40005 0)
			(size 0.4572 0.508)
			(layers "B.Cu" "B.Mask" "B.Paste")
			(net "GND")
		)
	)
	(footprint ""
		(layer "B.Cu")
		(at 79.60614 -185.598054 90)
		(property "Reference" "R883"
			(at 3.446272 -0.247142 270)
			(unlocked yes)
			(layer "B.SilkS")
			(effects
				(font
					(size 0.7874 0.5842)
					(thickness 0.1524)
				)
				(justify left mirror)
			)
		)
		(property "Value" ""
			(at 0 0 90)
			(layer "B.Fab")
			(effects
				(font
					(size 1.27 1.27)
				)
				(justify mirror)
			)
		)
		(duplicate_pad_numbers_are_jumpers no)
		(fp_line
			(start 0.7874 -0.4064)
			(end -0.7874 -0.4064)
			(stroke
				(width 0.1524)
				(type default)
			)
			(layer "B.SilkS")
		)
		(fp_line
			(start -0.7874 -0.4064)
			(end -0.7874 0.4064)
			(stroke
				(width 0.1524)
				(type default)
			)
			(layer "B.SilkS")
		)
		(fp_line
			(start 0.7874 0.4064)
			(end 0.7874 -0.4064)
			(stroke
				(width 0.1524)
				(type default)
			)
			(layer "B.SilkS")
		)
		(fp_line
			(start -0.7874 0.4064)
			(end 0.7874 0.4064)
			(stroke
				(width 0.1524)
				(type default)
			)
			(layer "B.SilkS")
		)
		(fp_poly
			(pts
				(xy 0.508 0.2794) (xy 0.508 0.2286) (xy 0.635 0.2286) (xy 0.635 -0.254) (xy 0.5334 -0.254) (xy 0.5334 -0.2794)
				(xy -0.5334 -0.2794) (xy -0.5334 -0.254) (xy -0.635 -0.254) (xy -0.635 0.254) (xy -0.5334 0.254)
				(xy -0.5334 0.2794)
			)
			(stroke
				(width 0)
				(type default)
			)
			(fill no)
			(layer "B.CrtYd")
		)
		(pad "1" smd rect
			(at -0.40005 0 270)
			(size 0.4572 0.508)
			(layers "B.Cu" "B.Mask" "B.Paste")
			(net "T3_NODE1_EN")
		)
		(pad "2" smd rect
			(at 0.40005 0 270)
			(size 0.4572 0.508)
			(layers "B.Cu" "B.Mask" "B.Paste")
			(net "T3_NODE1_EN_R")
		)
	)
)
